# BASEBOARD_FAB2 (Tioga Pass) — schematic netlist excerpt (pin names and nets, part order shuffled) for the footprints in the layout excerpt that follows; sources: Cadence DE-HDL packaged netlist, KiCad conversion of Wiwynn_Tioga_Pass_MB.brd

R1U10  RES  20.0 1% CHIP  pkg 0402  page 159 : A = SMB_SMLINK0_STBY_LVC3_SDA_R ; B = SMB_SMLINK0_STBY_LVC3_SDA
R1W41  RES  4.75K 1% CHIP  pkg 0402  page 188 : A = GND ; B = EXT_MDIO_I2C_SEL
C9U10  CAP_A  0.01UF 25V 10% X7R  pkg 0402V  page 81 : A = M_J_VREF ; B = GND

(kicad_pcb
	(version 20260206)
	(generator "pcbnew")
	(generator_version "10.0")
	(general
		(thickness 1.6)
		(legacy_teardrops no)
	)
	(paper "A4")
	(title_block
		(title "Wiwynn_Tioga_Pass_MB.brd")
		(comment 1 "Tioga Pass / footprints 3210-3212 of 4770")
	)
	(layers
		(0 "F.Cu" signal "TOP")
		(4 "In1.Cu" signal "L2GND")
		(6 "In2.Cu" signal "L3")
		(8 "In3.Cu" signal "L4GND")
		(10 "In4.Cu" signal "L5")
		(12 "In5.Cu" signal "L6GND")
		(14 "In6.Cu" signal "L7VCC")
		(16 "In7.Cu" signal "L8VCC")
		(18 "In8.Cu" signal "L9GND")
		(20 "In9.Cu" signal "L10")
		(22 "In10.Cu" signal "L11GND")
		(24 "In11.Cu" signal "L12")
		(26 "In12.Cu" signal "L13GND")
		(2 "B.Cu" signal "BOTTOM")
		(9 "F.Adhes" user "F.Adhesive")
		(11 "B.Adhes" user "B.Adhesive")
		(13 "F.Paste" user "Package Geometry/Pastemask Top")
		(15 "B.Paste" user "Package Geometry/Pastemask Bottom")
		(5 "F.SilkS" user "Ref Des/Silkscreen Top")
		(7 "B.SilkS" user "Ref Des/Silkscreen Bottom")
		(1 "F.Mask" user "Board Geometry/Soldermask Top")
		(3 "B.Mask" user "Board Geometry/Soldermask Bottom")
		(17 "Dwgs.User" user "User.Drawings")
		(19 "Cmts.User" user "User.Comments")
		(21 "Eco1.User" user "User.Eco1")
		(23 "Eco2.User" user "User.Eco2")
		(25 "Edge.Cuts" user "Board Geometry/Outline")
		(27 "Margin" user)
		(31 "F.CrtYd" user "Package Geometry/Place Bound Top")
		(29 "B.CrtYd" user "Package Geometry/Place Bound Bottom")
		(35 "F.Fab" user "Ref Des/Assembly Top")
		(33 "B.Fab" user "Ref Des/Assembly Bottom")
	)
	(footprint ""
		(layer "B.Cu")
		(at 443.46368 -58.01614 -90)
		(property "Reference" "R1W41"
			(at 0.8382 -0.67818 270)
			(unlocked yes)
			(layer "B.SilkS")
			(effects
				(font
					(size 0.4064 0.254)
					(thickness 0.1524)
				)
				(justify left mirror)
			)
		)
		(property "Value" ""
			(at 0 0 90)
			(layer "B.Fab")
			(effects
				(font
					(size 1.27 1.27)
				)
				(justify mirror)
			)
		)
		(duplicate_pad_numbers_are_jumpers no)
		(fp_poly
			(pts
				(xy 0.2794 -0.1016) (xy -0.2794 -0.1016) (xy -0.2794 0.9906) (xy 0.2794 0.9906)
			)
			(stroke
				(width 0)
				(type default)
			)
			(fill no)
			(layer "B.CrtYd")
		)
		(fp_line
			(start -0.2794 0.9906)
			(end -0.2794 -0.1016)
			(stroke
				(width 0.1)
				(type default)
			)
			(layer "B.Fab")
		)
		(fp_line
			(start 0.2794 0.9906)
			(end -0.2794 0.9906)
			(stroke
				(width 0.1)
				(type default)
			)
			(layer "B.Fab")
		)
		(fp_line
			(start -0.2794 -0.1016)
			(end 0.2794 -0.1016)
			(stroke
				(width 0.1)
				(type default)
			)
			(layer "B.Fab")
		)
		(fp_line
			(start 0.2794 -0.1016)
			(end 0.2794 0.9906)
			(stroke
				(width 0.1)
				(type default)
			)
			(layer "B.Fab")
		)
		(pad "1" smd rect
			(at 0 0 90)
			(size 0.508 0.508)
			(layers "B.Cu" "B.Mask" "B.Paste")
			(net "GND")
		)
		(pad "2" smd rect
			(at 0 0.889 90)
			(size 0.508 0.508)
			(layers "B.Cu" "B.Mask" "B.Paste")
			(net "EXT_MDIO_I2C_SEL")
		)
		(zone
			(layer "B.Cu")
			(hatch none 0.5)
			(connect_pads
				(clearance 0)
			)
			(min_thickness 0.25)
			(keepout
				(tracks not_allowed)
				(vias allowed)
				(pads allowed)
				(copperpour not_allowed)
				(footprints allowed)
			)
			(placement
				(enabled no)
				(sheetname "")
			)
			(fill
				(thermal_gap 0.5)
				(thermal_bridge_width 0.5)
				(island_removal_mode 0)
			)
			(polygon
				(pts
					(xy 442.82868 -57.76214) (xy 442.82868 -58.27014) (xy 443.20968 -58.27014) (xy 443.20968 -57.76214)
				)
			)
		)
		(zone
			(layer "B.Cu")
			(hatch none 0.5)
			(connect_pads
				(clearance 0)
			)
			(min_thickness 0.25)
			(keepout
				(tracks allowed)
				(vias not_allowed)
				(pads allowed)
				(copperpour not_allowed)
				(footprints allowed)
			)
			(placement
				(enabled no)
				(sheetname "")
			)
			(fill
				(thermal_gap 0.5)
				(thermal_bridge_width 0.5)
				(island_removal_mode 0)
			)
			(polygon
				(pts
					(xy 443.20968 -57.76214) (xy 443.20968 -58.27014) (xy 442.82868 -58.27014) (xy 442.82868 -57.76214)
				)
			)
		)
	)
	(footprint ""
		(layer "B.Cu")
		(at 427.4185 -21.082 90)
		(property "Reference" "R1U10"
			(at 0 0 90)
			(layer "B.SilkS")
			(hide yes)
			(effects
				(font
					(size 1.27 1.27)
				)
				(justify mirror)
			)
		)
		(property "Value" ""
			(at 0 0 90)
			(layer "B.Fab")
			(effects
				(font
					(size 1.27 1.27)
				)
				(justify mirror)
			)
		)
		(duplicate_pad_numbers_are_jumpers no)
		(fp_poly
			(pts
				(xy 0.2794 -0.1016) (xy -0.2794 -0.1016) (xy -0.2794 0.9906) (xy 0.2794 0.9906)
			)
			(stroke
				(width 0)
				(type default)
			)
			(fill no)
			(layer "B.CrtYd")
		)
		(fp_line
			(start 0.2794 -0.1016)
			(end 0.2794 0.9906)
			(stroke
				(width 0.1)
				(type default)
			)
			(layer "B.Fab")
		)
		(fp_line
			(start -0.2794 -0.1016)
			(end 0.2794 -0.1016)
			(stroke
				(width 0.1)
				(type default)
			)
			(layer "B.Fab")
		)
		(fp_line
			(start 0.2794 0.9906)
			(end -0.2794 0.9906)
			(stroke
				(width 0.1)
				(type default)
			)
			(layer "B.Fab")
		)
		(fp_line
			(start -0.2794 0.9906)
			(end -0.2794 -0.1016)
			(stroke
				(width 0.1)
				(type default)
			)
			(layer "B.Fab")
		)
		(pad "1" smd rect
			(at 0 0 270)
			(size 0.508 0.508)
			(layers "B.Cu" "B.Mask" "B.Paste")
			(net "SMB_SMLINK0_STBY_LVC3_SDA_R")
		)
		(pad "2" smd rect
			(at 0 0.889 270)
			(size 0.508 0.508)
			(layers "B.Cu" "B.Mask" "B.Paste")
			(net "SMB_SMLINK0_STBY_LVC3_SDA")
		)
		(zone
			(layer "B.Cu")
			(hatch none 0.5)
			(connect_pads
				(clearance 0)
			)
			(min_thickness 0.25)
			(keepout
				(tracks allowed)
				(vias not_allowed)
				(pads allowed)
				(copperpour not_allowed)
				(footprints allowed)
			)
			(placement
				(enabled no)
				(sheetname "")
			)
			(fill
				(thermal_gap 0.5)
				(thermal_bridge_width 0.5)
				(island_removal_mode 0)
			)
			(polygon
				(pts
					(xy 427.6725 -21.336) (xy 427.6725 -20.828) (xy 428.0535 -20.828) (xy 428.0535 -21.336)
				)
			)
		)
		(zone
			(layer "B.Cu")
			(hatch none 0.5)
			(connect_pads
				(clearance 0)
			)
			(min_thickness 0.25)
			(keepout
				(tracks not_allowed)
				(vias allowed)
				(pads allowed)
				(copperpour not_allowed)
				(footprints allowed)
			)
			(placement
				(enabled no)
				(sheetname "")
			)
			(fill
				(thermal_gap 0.5)
				(thermal_bridge_width 0.5)
				(island_removal_mode 0)
			)
			(polygon
				(pts
					(xy 428.0535 -21.336) (xy 428.0535 -20.828) (xy 427.6725 -20.828) (xy 427.6725 -21.336)
				)
			)
		)
	)
	(footprint ""
		(layer "B.Cu")
		(at 30.452568 1.524 90)
		(property "Reference" "C9U10"
			(at 0 0 90)
			(layer "B.SilkS")
			(hide yes)
			(effects
				(font
					(size 1.27 1.27)
				)
				(justify mirror)
			)
		)
		(property "Value" ""
			(at 0 0 90)
			(layer "B.Fab")
			(effects
				(font
					(size 1.27 1.27)
				)
				(justify mirror)
			)
		)
		(duplicate_pad_numbers_are_jumpers no)
		(fp_poly
			(pts
				(xy -0.3048 -0.1016) (xy -0.3048 0.9906) (xy 0.3048 0.9906) (xy 0.3048 -0.1016)
			)
			(stroke
				(width 0)
				(type default)
			)
			(fill no)
			(layer "B.CrtYd")
		)
		(fp_line
			(start 0.3048 -0.1016)
			(end 0.3048 0.9906)
			(stroke
				(width 0.1)
				(type default)
			)
			(layer "B.Fab")
		)
		(fp_line
			(start -0.3048 -0.1016)
			(end 0.3048 -0.1016)
			(stroke
				(width 0.1)
				(type default)
			)
			(layer "B.Fab")
		)
		(fp_line
			(start 0.3048 0.9906)
			(end -0.3048 0.9906)
			(stroke
				(width 0.1)
				(type default)
			)
			(layer "B.Fab")
		)
		(fp_line
			(start -0.3048 0.9906)
			(end -0.3048 -0.1016)
			(stroke
				(width 0.1)
				(type default)
			)
			(layer "B.Fab")
		)
		(pad "1" smd rect
			(at 0 0 270)
			(size 0.508 0.508)
			(layers "B.Cu" "B.Mask" "B.Paste")
			(net "M_J_VREF")
		)
		(pad "2" smd rect
			(at 0 0.889 270)
			(size 0.508 0.508)
			(layers "B.Cu" "B.Mask" "B.Paste")
			(net "GND")
		)
		(zone
			(layer "B.Cu")
			(hatch none 0.5)
			(connect_pads
				(clearance 0)
			)
			(min_thickness 0.25)
			(keepout
				(tracks allowed)
				(vias not_allowed)
				(pads allowed)
				(copperpour not_allowed)
				(footprints allowed)
			)
			(placement
				(enabled no)
				(sheetname "")
			)
			(fill
				(thermal_gap 0.5)
				(thermal_bridge_width 0.5)
				(island_removal_mode 0)
			)
			(polygon
				(pts
					(xy 30.706568 1.27) (xy 30.706568 1.778) (xy 31.087568 1.778) (xy 31.087568 1.27)
				)
			)
		)
		(zone
			(layer "B.Cu")
			(hatch none 0.5)
			(connect_pads
				(clearance 0)
			)
			(min_thickness 0.25)
			(keepout
				(tracks not_allowed)
				(vias allowed)
				(pads allowed)
				(copperpour not_allowed)
				(footprints allowed)
			)
			(placement
				(enabled no)
				(sheetname "")
			)
			(fill
				(thermal_gap 0.5)
				(thermal_bridge_width 0.5)
				(island_removal_mode 0)
			)
			(polygon
				(pts
					(xy 31.087568 1.27) (xy 31.087568 1.778) (xy 30.706568 1.778) (xy 30.706568 1.27)
				)
			)
		)
	)
)
